FILE_TYPE = CONNECTIVITY;
{Allegro Design Entry HDL 17.2-2016 S081 (4005846) 1/11/2022}
"PAGE_NUMBER" = 56;
0"NC";
1"SPI_CPU1_CLK";
2"SPI_CPU1_R_CLK";
3"PD_ESPI_CPU1_CLK2";
4"NC_CPU1_USB3_USB11_TXN";
5"NC_CPU1_USB3_USB11_TXP";
6"NC_CPU1_USB10_OC_N";
7"NC_CPU1_USB11_OC_N";
8"NC_CPU1_USB00_OC_N";
9"NC_CPU1_USB01_OC_N";
10"NC_CPU1_USB2_USB00_DN";
11"NC_CPU1_USB2_USB00_DP";
12"NC_CPU1_USB3_USB00_RXN";
13"NC_CPU1_USB3_USB00_RXP";
14"NC_CPU1_USB3_USB00_TXP";
15"NC_CPU1_USB3_USB00_TXN";
16"NC_CPU1_USB2_USB01_DN";
17"NC_CPU1_USB2_USB01_DP";
18"NC_CPU1_USB3_USB01_RXN";
19"NC_CPU1_USB3_USB01_RXP";
20"NC_CPU1_USB3_USB01_TXN";
21"NC_CPU1_USB3_USB01_TXP";
22"NC_CPU1_USB2_USB10_DN";
23"NC_CPU1_USB2_USB10_DP";
24"NC_CPU1_USB3_USB10_RXN";
25"NC_CPU1_USB3_USB10_RXP";
26"NC_CPU1_USB3_USB10_TXN";
27"NC_CPU1_USB3_USB10_TXP";
28"NC_CPU1_USB2_USB11_DN";
29"NC_CPU1_USB2_USB11_DP";
30"NC_CPU1_USB3_USB11_RXN";
31"NC_CPU1_USB3_USB11_RXP";
%"Q_RES"
"1","(-6800,5500)","0","pure_quanta","I11";
;
LOCATION"R738"
$SEC"1"
CDS_SEC"1"
VALUE"33"
CDS_LIB"pure_quanta"
WATTAGE"1/16W"
MATERIAL"CHIP"
TOLERANCE"5%"
PART_NUMBER"CS03302JB29"
PACK_TYPE"0402LF";
"B"
$PN"2"2;
"A"
$PN"1"1;
%"GENOA_SP5"
"22","(-4525,4675)","0","pure_quanta","I8";
;
LOCATION"U26"
$SEC"22"
CDS_SEC"22"
PART_TYPE"SMLF"
MATERIAL"IO"
VALUE"SOCKET6096_13568-001"
PART_NUMBER"DGA^6000030"
NEEDS_NO_SIZE"TRUE"
CDS_LMAN_SYM_OUTLINE"-1100,1225,1100,-1225"
CDS_LIB"pure_quanta";
"ESPI_RSTOUT_L||AGPIO23"
$PN"DE27"0;
"ESPI_CLK1||SPI_CLK1||AGPIO75"
$PN"DG23"0;
"ESPI_CLK2||AGPIO74"
$PN"DF27"3;
"ESPI0_ALERT_L||AGPIO108"
$PN"DJ22"0;
"AGPIO76||SPI_TPM_CS_L"
$PN"DJ25"0;
"ESPI_CLK0||SPI_CLK0||AGPIO117"
$PN"DJ27"2;
"ESPI1_ALERT_L||AGPIO110"
$PN"DF24"0;
"ESPI_RSTIN_L||KBRST_L||AGPIO129"
$PN"DJ26"0;
"USB01_OC_L||AGPIO265"
$PN"E24"9;
"SPI_CS1_L||AGPIO119"
$PN"DG26"0;
"SPI_CS2_L||AGPIO126"
$PN"DH27"0;
"ESPI0_DAT0||SPI0_DAT0||AGPIO120"
$PN"DF28"0;
"ESPI0_DAT1||SPI0_DAT1||AGPIO121"
$PN"DG22"0;
"ESPI0_DAT2||SPI0_DAT2||AGPIO122"
$PN"DJ28"0;
"ESPI0_DAT3||SPI0_DAT3||AGPIO123"
$PN"DG29"0;
"ESPI1_DAT2||SPI1_DAT2||AGPIO133"
$PN"DF25"0;
"ESPI1_DAT3||SPI1_DAT3||AGPIO134"
$PN"DG25"0;
"ESPI_CS1_L||AGPIO125"
$PN"DJ23"0;
"ESPI1_DAT0||SPI1_DAT0||AGPIO131"
$PN"DH24"0;
"ESPI1_DAT1||SPI1_DAT1||AGPIO132"
$PN"DE24"0;
"SPI_CS0_L||AGPIO118"
$PN"DF30"0;
"USB00_OC_L||AGPIO264"
$PN"E23"8;
"ESPI_CS0_L||AGPIO124"
$PN"DG28"0;
"USB11_OC_L||AGPIO17"
$PN"DH40"7;
"USB10_OC_L||AGPIO16"
$PN"DG40"6;
"USB11_TXP"
$PN"DG58"5;
"USB11_TXN"
$PN"DH58"4;
"USB11_RXP"
$PN"DJ62"31;
"USB11_RXN"
$PN"DH62"30;
"USB11_DP"
$PN"DH60"29;
"USB11_DN"
$PN"DJ60"28;
"USB10_TXP"
$PN"DH69"27;
"USB10_TXN"
$PN"DJ69"26;
"USB10_RXP"
$PN"DJ65"25;
"USB10_RXN"
$PN"DH65"24;
"USB10_DP"
$PN"DJ67"23;
"USB10_DN"
$PN"DH67"22;
"USB01_TXP"
$PN"E30"21;
"USB01_TXN"
$PN"E29"20;
"USB01_RXP"
$PN"C29"19;
"USB01_RXN"
$PN"C28"18;
"USB01_DP"
$PN"A28"17;
"USB01_DN"
$PN"A29"16;
"USB00_TXP"
$PN"C25"15;
"USB00_TXN"
$PN"C26"14;
"USB00_RXP"
$PN"E27"13;
"USB00_RXN"
$PN"E26"12;
"USB00_DP"
$PN"A26"11;
"USB00_DN"
$PN"A25"10;
END.
